# S9S_MB_2U (Grand Teton) — schematic netlist excerpt (pin names and nets, part order shuffled) for the footprints in the layout excerpt that follows; sources: Cadence DE-HDL packaged netlist, KiCad conversion of 03242023_DA0F0TMBIJ0_F0T_Motherboard_J_brd_V01_OCP.brd

C2069  Q_CAP  0.1UF 25V 10% X7R  pkg 0402  page 171 : A = P3V3_E1S_0_R ; B = GND
C1201  Q_CAP  22UF 6.3V 20% X6S  pkg C0603  page 189 : A = P3V3_AUX ; B = GND

(kicad_pcb
	(version 20260206)
	(generator "pcbnew")
	(generator_version "10.0")
	(general
		(thickness 1.6)
		(legacy_teardrops no)
	)
	(paper "A4")
	(title_block
		(title "03242023_DA0F0TMBIJ0_F0T_Motherboard_J_brd_V01_OCP.brd")
		(comment 1 "Grand Teton / footprints 4722-4723 of 6105")
	)
	(layers
		(0 "F.Cu" signal "TOP")
		(4 "In1.Cu" signal "GND")
		(6 "In2.Cu" signal "IN1")
		(8 "In3.Cu" signal "GND1")
		(10 "In4.Cu" signal "IN2")
		(12 "In5.Cu" signal "GND2")
		(14 "In6.Cu" signal "IN3")
		(16 "In7.Cu" signal "GND3")
		(18 "In8.Cu" signal "VCC")
		(20 "In9.Cu" signal "VCC1")
		(22 "In10.Cu" signal "GND4")
		(24 "In11.Cu" signal "IN4")
		(26 "In12.Cu" signal "GND5")
		(28 "In13.Cu" signal "IN5")
		(30 "In14.Cu" signal "GND6")
		(32 "In15.Cu" signal "IN6")
		(34 "In16.Cu" signal "GND7")
		(2 "B.Cu" signal "BOTTOM")
		(9 "F.Adhes" user "F.Adhesive")
		(11 "B.Adhes" user "B.Adhesive")
		(13 "F.Paste" user "Package Geometry/Pastemask Top")
		(15 "B.Paste" user "Package Geometry/Pastemask Bottom")
		(5 "F.SilkS" user "Ref Des/Silkscreen Top")
		(7 "B.SilkS" user "Ref Des/Silkscreen Bottom")
		(1 "F.Mask" user "Board Geometry/Soldermask Top")
		(3 "B.Mask" user "Board Geometry/Soldermask Bottom")
		(17 "Dwgs.User" user "User.Drawings")
		(19 "Cmts.User" user "User.Comments")
		(21 "Eco1.User" user "User.Eco1")
		(23 "Eco2.User" user "User.Eco2")
		(25 "Edge.Cuts" user "Board Geometry/Outline")
		(27 "Margin" user)
		(31 "F.CrtYd" user "Package Geometry/Place Bound Top")
		(29 "B.CrtYd" user "Package Geometry/Place Bound Bottom")
		(35 "F.Fab" user "Ref Des/Assembly Top")
		(33 "B.Fab" user "Ref Des/Assembly Bottom")
	)
	(footprint ""
		(layer "B.Cu")
		(at 216.18448 -54.955948)
		(property "Reference" "C2069"
			(at 0 0 0)
			(layer "B.SilkS")
			(hide yes)
			(effects
				(font
					(size 1.27 1.27)
				)
				(justify mirror)
			)
		)
		(property "Value" ""
			(at 0 0 0)
			(layer "B.Fab")
			(effects
				(font
					(size 1.27 1.27)
				)
				(justify mirror)
			)
		)
		(duplicate_pad_numbers_are_jumpers no)
		(fp_line
			(start -0.7874 -0.4064)
			(end -0.7874 0.4064)
			(stroke
				(width 0.1524)
				(type default)
			)
			(layer "B.SilkS")
		)
		(fp_line
			(start -0.7874 0.4064)
			(end 0.7874 0.4064)
			(stroke
				(width 0.1524)
				(type default)
			)
			(layer "B.SilkS")
		)
		(fp_line
			(start 0.7874 -0.4064)
			(end -0.7874 -0.4064)
			(stroke
				(width 0.1524)
				(type default)
			)
			(layer "B.SilkS")
		)
		(fp_line
			(start 0.7874 0.4064)
			(end 0.7874 -0.4064)
			(stroke
				(width 0.1524)
				(type default)
			)
			(layer "B.SilkS")
		)
		(fp_line
			(start -0.67945 -0.3048)
			(end -0.67945 0.3048)
			(stroke
				(width 0.1)
				(type default)
			)
			(layer "B.Fab")
		)
		(fp_line
			(start -0.67945 0.3048)
			(end -0.120396 0.3048)
			(stroke
				(width 0.1)
				(type default)
			)
			(layer "B.Fab")
		)
		(fp_line
			(start -0.12065 -0.3048)
			(end -0.67945 -0.3048)
			(stroke
				(width 0.1)
				(type default)
			)
			(layer "B.Fab")
		)
		(fp_line
			(start -0.12065 -0.2794)
			(end -0.12065 -0.3048)
			(stroke
				(width 0.1)
				(type default)
			)
			(layer "B.Fab")
		)
		(fp_line
			(start -0.120396 0.2794)
			(end 0.12065 0.2794)
			(stroke
				(width 0.1)
				(type default)
			)
			(layer "B.Fab")
		)
		(fp_line
			(start -0.120396 0.3048)
			(end -0.120396 0.2794)
			(stroke
				(width 0.1)
				(type default)
			)
			(layer "B.Fab")
		)
		(fp_line
			(start 0.12065 -0.305054)
			(end 0.12065 -0.2794)
			(stroke
				(width 0.1)
				(type default)
			)
			(layer "B.Fab")
		)
		(fp_line
			(start 0.12065 -0.2794)
			(end -0.12065 -0.2794)
			(stroke
				(width 0.1)
				(type default)
			)
			(layer "B.Fab")
		)
		(fp_line
			(start 0.12065 0.2794)
			(end 0.12065 0.3048)
			(stroke
				(width 0.1)
				(type default)
			)
			(layer "B.Fab")
		)
		(fp_line
			(start 0.12065 0.3048)
			(end 0.67945 0.3048)
			(stroke
				(width 0.1)
				(type default)
			)
			(layer "B.Fab")
		)
		(fp_line
			(start 0.67945 -0.305054)
			(end 0.12065 -0.305054)
			(stroke
				(width 0.1)
				(type default)
			)
			(layer "B.Fab")
		)
		(fp_line
			(start 0.67945 0.3048)
			(end 0.67945 -0.305054)
			(stroke
				(width 0.1)
				(type default)
			)
			(layer "B.Fab")
		)
		(pad "1" smd circle
			(at 0.40005 0 180)
			(size 0 0)
			(layers "B.Cu" "B.Mask" "B.Paste")
			(net "P3V3_E1S_0_R")
		)
		(pad "2" smd circle
			(at -0.40005 0 180)
			(size 0 0)
			(layers "B.Cu" "B.Mask" "B.Paste")
			(net "GND")
		)
	)
	(footprint ""
		(layer "B.Cu")
		(at 324.332854 -66.83375 -90)
		(property "Reference" "C1201"
			(at 0 0 90)
			(layer "B.SilkS")
			(hide yes)
			(effects
				(font
					(size 1.27 1.27)
				)
				(justify mirror)
			)
		)
		(property "Value" ""
			(at 0 0 90)
			(layer "B.Fab")
			(effects
				(font
					(size 1.27 1.27)
				)
				(justify mirror)
			)
		)
		(duplicate_pad_numbers_are_jumpers no)
		(fp_line
			(start -1.2954 0.5842)
			(end 1.2954 0.5842)
			(stroke
				(width 0.1524)
				(type default)
			)
			(layer "B.SilkS")
		)
		(fp_line
			(start 1.2954 0.5842)
			(end 1.2954 -0.5842)
			(stroke
				(width 0.1524)
				(type default)
			)
			(layer "B.SilkS")
		)
		(fp_line
			(start -1.2954 -0.5842)
			(end -1.2954 0.5842)
			(stroke
				(width 0.1524)
				(type default)
			)
			(layer "B.SilkS")
		)
		(fp_line
			(start 0 -0.5842)
			(end 0 0.5842)
			(stroke
				(width 0.1524)
				(type default)
			)
			(layer "B.SilkS")
		)
		(fp_line
			(start 1.2954 -0.5842)
			(end -1.2954 -0.5842)
			(stroke
				(width 0.1524)
				(type default)
			)
			(layer "B.SilkS")
		)
		(fp_line
			(start -0.8636 0.4572)
			(end 0.8636 0.4572)
			(stroke
				(width 0.1)
				(type default)
			)
			(layer "B.Fab")
		)
		(fp_line
			(start 0.8636 0.4572)
			(end 0.8636 0.4064)
			(stroke
				(width 0.1)
				(type default)
			)
			(layer "B.Fab")
		)
		(fp_line
			(start -1.1938 0.4064)
			(end -0.8636 0.4064)
			(stroke
				(width 0.1)
				(type default)
			)
			(layer "B.Fab")
		)
		(fp_line
			(start -0.8636 0.4064)
			(end -0.8636 0.4572)
			(stroke
				(width 0.1)
				(type default)
			)
			(layer "B.Fab")
		)
		(fp_line
			(start 0.8636 0.4064)
			(end 1.1938 0.4064)
			(stroke
				(width 0.1)
				(type default)
			)
			(layer "B.Fab")
		)
		(fp_line
			(start 1.1938 0.4064)
			(end 1.1938 -0.4064)
			(stroke
				(width 0.1)
				(type default)
			)
			(layer "B.Fab")
		)
		(fp_line
			(start -1.1938 -0.4064)
			(end -1.1938 0.4064)
			(stroke
				(width 0.1)
				(type default)
			)
			(layer "B.Fab")
		)
		(fp_line
			(start -0.8636 -0.4064)
			(end -1.1938 -0.4064)
			(stroke
				(width 0.1)
				(type default)
			)
			(layer "B.Fab")
		)
		(fp_line
			(start 0.8636 -0.4064)
			(end 0.8636 -0.4572)
			(stroke
				(width 0.1)
				(type default)
			)
			(layer "B.Fab")
		)
		(fp_line
			(start 1.1938 -0.4064)
			(end 0.8636 -0.4064)
			(stroke
				(width 0.1)
				(type default)
			)
			(layer "B.Fab")
		)
		(fp_line
			(start -0.8636 -0.4572)
			(end -0.8636 -0.4064)
			(stroke
				(width 0.1)
				(type default)
			)
			(layer "B.Fab")
		)
		(fp_line
			(start 0.8636 -0.4572)
			(end -0.8636 -0.4572)
			(stroke
				(width 0.1)
				(type default)
			)
			(layer "B.Fab")
		)
		(pad "1" smd rect
			(at 0.7366 0 180)
			(size 0.7112 0.8128)
			(layers "B.Cu" "B.Mask" "B.Paste")
			(net "P3V3_AUX")
		)
		(pad "2" smd rect
			(at -0.7366 0 180)
			(size 0.7112 0.8128)
			(layers "B.Cu" "B.Mask" "B.Paste")
			(net "GND")
		)
	)
)
